# T6G (Grand Teton) — schematic netlist excerpt (pin names and nets, part order shuffled) for the footprints in the layout excerpt that follows; sources: Cadence DE-HDL packaged netlist, KiCad conversion of 04192023_DAF0TMB3IC0_F0TG_MB_C_brd_V02_OCP.brd

PU52  ISL99390FRZTR5935  ISL99390FRZ-TR5935 IC  pkg QFN21_6X5XB  page 223
  VOS  = PVDDIO_P1_VOS3
  AGND  = GND
  VCC  = PVDDIO_P1_VCC3
  PVCC  = PVDDCR_CPU1_P1_PVCC
  PGND1  = GND
  GL1  = NC_PVDDIO_P1_GL1_3
  PGND2  = GND
  SW  = SW_PVDDIO_P1_SW3
  VIN1  = SW_P12V_AUX_PVDDIO_P1_FLT
  VIN2  = SW_P12V_AUX_PVDDIO_P1_FLT
  DNC  = NC_PVDDIO_P1_DNC3
  PHASE  = SW_PVDDIO_P1_BOOTR3
  BOOT  = SW_PVDDIO_P1_BOOT3
  PWM  = PVDDIO_P1_PWM3
  EN  = PVDDIO_P1_VCC3
  TOUT_FLT  = PVDDIO_P1_TEMP1
  LSET  = PVDDIO_P1_LSET3
  IOUT  = PVDDIO_P1_IMON3
  REFIN  = PVDDCR_CPU1_P1_VCCS
  PGND3  = GND
  GL2  = NC_PVDDIO_P1_GL2_3

(kicad_pcb
	(version 20260206)
	(generator "pcbnew")
	(generator_version "10.0")
	(general
		(thickness 1.6)
		(legacy_teardrops no)
	)
	(paper "A4")
	(title_block
		(title "04192023_DAF0TMB3IC0_F0TG_MB_C_brd_V02_OCP.brd")
		(comment 1 "Grand Teton / footprints 4611-4611 of 8354")
	)
	(layers
		(0 "F.Cu" signal "TOP")
		(4 "In1.Cu" signal "GND")
		(6 "In2.Cu" signal "IN1")
		(8 "In3.Cu" signal "GND1")
		(10 "In4.Cu" signal "IN2")
		(12 "In5.Cu" signal "GND2")
		(14 "In6.Cu" signal "IN3")
		(16 "In7.Cu" signal "GND3")
		(18 "In8.Cu" signal "VCC")
		(20 "In9.Cu" signal "VCC1")
		(22 "In10.Cu" signal "GND4")
		(24 "In11.Cu" signal "IN4")
		(26 "In12.Cu" signal "GND5")
		(28 "In13.Cu" signal "IN5")
		(30 "In14.Cu" signal "GND6")
		(32 "In15.Cu" signal "IN6")
		(34 "In16.Cu" signal "GND7")
		(2 "B.Cu" signal "BOTTOM")
		(9 "F.Adhes" user "F.Adhesive")
		(11 "B.Adhes" user "B.Adhesive")
		(13 "F.Paste" user "Package Geometry/Pastemask Top")
		(15 "B.Paste" user "Package Geometry/Pastemask Bottom")
		(5 "F.SilkS" user "Ref Des/Silkscreen Top")
		(7 "B.SilkS" user "Ref Des/Silkscreen Bottom")
		(1 "F.Mask" user "Board Geometry/Soldermask Top")
		(3 "B.Mask" user "Board Geometry/Soldermask Bottom")
		(17 "Dwgs.User" user "User.Drawings")
		(19 "Cmts.User" user "User.Comments")
		(21 "Eco1.User" user "User.Eco1")
		(23 "Eco2.User" user "User.Eco2")
		(25 "Edge.Cuts" user "Board Geometry/Outline")
		(27 "Margin" user)
		(31 "F.CrtYd" user "Package Geometry/Place Bound Top")
		(29 "B.CrtYd" user "Package Geometry/Place Bound Bottom")
		(35 "F.Fab" user "Ref Des/Assembly Top")
		(33 "B.Fab" user "Ref Des/Assembly Bottom")
	)
	(footprint ""
		(layer "F.Cu")
		(at 36.881054 -346.721176)
		(property "Reference" "PU52"
			(at -2.972054 -7.709154 0)
			(unlocked yes)
			(layer "F.SilkS")
			(effects
				(font
					(size 0.7874 0.5842)
					(thickness 0.1524)
				)
				(justify left)
			)
		)
		(property "Value" ""
			(at 0 0 0)
			(layer "F.Fab")
			(effects
				(font
					(size 1.27 1.27)
				)
			)
		)
		(duplicate_pad_numbers_are_jumpers no)
		(fp_line
			(start -2.500122 -2.999994)
			(end -2.24409 -2.999994)
			(stroke
				(width 0.1524)
				(type default)
			)
			(layer "F.SilkS")
		)
		(fp_line
			(start -2.500122 -2.529078)
			(end -2.500122 -2.999994)
			(stroke
				(width 0.1524)
				(type default)
			)
			(layer "F.SilkS")
		)
		(fp_line
			(start -2.500122 0.6604)
			(end -2.500122 0.229108)
			(stroke
				(width 0.1524)
				(type default)
			)
			(layer "F.SilkS")
		)
		(fp_line
			(start -2.500122 2.999994)
			(end -2.500122 2.339594)
			(stroke
				(width 0.1524)
				(type default)
			)
			(layer "F.SilkS")
		)
		(fp_line
			(start -2.2987 2.999994)
			(end -2.500122 2.999994)
			(stroke
				(width 0.1524)
				(type default)
			)
			(layer "F.SilkS")
		)
		(fp_line
			(start 2.31394 -2.999994)
			(end 2.500122 -2.999994)
			(stroke
				(width 0.1524)
				(type default)
			)
			(layer "F.SilkS")
		)
		(fp_line
			(start 2.500122 -2.999994)
			(end 2.500122 -2.44348)
			(stroke
				(width 0.1524)
				(type default)
			)
			(layer "F.SilkS")
		)
		(fp_line
			(start 2.500122 2.339594)
			(end 2.500122 2.999994)
			(stroke
				(width 0.1524)
				(type default)
			)
			(layer "F.SilkS")
		)
		(fp_line
			(start 2.500122 2.999994)
			(end 2.2987 2.999994)
			(stroke
				(width 0.1524)
				(type default)
			)
			(layer "F.SilkS")
		)
		(fp_poly
			(pts
				(xy -2.785872 -2.44094) (xy -3.45948 -2.665476) (xy -3.010408 -3.114548)
			)
			(stroke
				(width 0)
				(type default)
			)
			(fill yes)
			(layer "F.SilkS")
		)
		(fp_line
			(start -2.500122 -2.999994)
			(end 2.500122 -2.999994)
			(stroke
				(width 0.1)
				(type default)
			)
			(layer "F.Fab")
		)
		(fp_line
			(start -2.500122 2.999994)
			(end -2.500122 -2.999994)
			(stroke
				(width 0.1)
				(type default)
			)
			(layer "F.Fab")
		)
		(fp_line
			(start 2.500122 -2.999994)
			(end 2.500122 2.999994)
			(stroke
				(width 0.1)
				(type default)
			)
			(layer "F.Fab")
		)
		(fp_line
			(start 2.500122 2.999994)
			(end -2.500122 2.999994)
			(stroke
				(width 0.1)
				(type default)
			)
			(layer "F.Fab")
		)
		(fp_poly
			(pts
				(xy -4.218432 -2.783078) (xy -4.218432 -1.767078) (xy -3.202432 -2.275078)
			)
			(stroke
				(width 0)
				(type default)
			)
			(fill yes)
			(layer "F.Fab")
		)
		(pad "1" smd rect
			(at -2.400046 -2.275078 90)
			(size 0.2286 0.6096)
			(layers "F.Cu" "F.Mask" "F.Paste")
			(net "PVDDIO_P1_VOS3")
		)
		(pad "2" smd rect
			(at -2.400046 -1.82499 90)
			(size 0.2286 0.6096)
			(layers "F.Cu" "F.Mask" "F.Paste")
			(net "GND")
		)
		(pad "3" smd rect
			(at -2.400046 -1.374902 90)
			(size 0.2286 0.6096)
			(layers "F.Cu" "F.Mask" "F.Paste")
			(net "PVDDIO_P1_VCC3")
		)
		(pad "4" smd rect
			(at -2.400046 -0.925068 90)
			(size 0.2286 0.6096)
			(layers "F.Cu" "F.Mask" "F.Paste")
			(net "PVDDCR_CPU1_P1_PVCC")
		)
		(pad "5" smd rect
			(at -2.400046 -0.47498 90)
			(size 0.2286 0.6096)
			(layers "F.Cu" "F.Mask" "F.Paste")
			(net "GND")
		)
		(pad "6" smd rect
			(at -2.400046 -0.024892 90)
			(size 0.2286 0.6096)
			(layers "F.Cu" "F.Mask" "F.Paste")
			(net "NC_PVDDIO_P1_GL1_3")
		)
		(pad "7_9-20_24" smd circle
			(at 0 1.150112 90)
			(size 0 0)
			(layers "F.Cu" "F.Mask" "F.Paste")
			(net "GND")
		)
		(pad "10_19" smd rect
			(at 0 2.899918 90)
			(size 0.6096 4.318)
			(layers "F.Cu" "F.Mask" "F.Paste")
			(net "SW_PVDDIO_P1_SW3")
		)
		(pad "25_29" smd rect
			(at 1.549908 -1.279906 270)
			(size 2.0574 2.3114)
			(layers "F.Cu" "F.Mask" "F.Paste")
			(net "SW_P12V_AUX_PVDDIO_P1_FLT")
		)
		(pad "30" smd rect
			(at 2.05994 -2.899918)
			(size 0.2286 0.6096)
			(layers "F.Cu" "F.Mask" "F.Paste")
			(net "SW_P12V_AUX_PVDDIO_P1_FLT")
		)
		(pad "31" smd rect
			(at 1.610106 -2.899918)
			(size 0.2286 0.6096)
			(layers "F.Cu" "F.Mask" "F.Paste")
			(net "NC_PVDDIO_P1_DNC3")
		)
		(pad "32" smd rect
			(at 1.160018 -2.899918)
			(size 0.2286 0.6096)
			(layers "F.Cu" "F.Mask" "F.Paste")
			(net "SW_PVDDIO_P1_BOOTR3")
		)
		(pad "33" smd rect
			(at 0.70993 -2.899918)
			(size 0.2286 0.6096)
			(layers "F.Cu" "F.Mask" "F.Paste")
			(net "SW_PVDDIO_P1_BOOT3")
		)
		(pad "34" smd rect
			(at 0.260096 -2.899918)
			(size 0.2286 0.6096)
			(layers "F.Cu" "F.Mask" "F.Paste")
			(net "PVDDIO_P1_PWM3")
		)
		(pad "35" smd rect
			(at -0.189992 -2.899918)
			(size 0.2286 0.6096)
			(layers "F.Cu" "F.Mask" "F.Paste")
			(net "PVDDIO_P1_VCC3")
		)
		(pad "36" smd rect
			(at -0.64008 -2.899918)
			(size 0.2286 0.6096)
			(layers "F.Cu" "F.Mask" "F.Paste")
			(net "PVDDIO_P1_TEMP1")
		)
		(pad "37" smd rect
			(at -1.089914 -2.899918)
			(size 0.2286 0.6096)
			(layers "F.Cu" "F.Mask" "F.Paste")
			(net "PVDDIO_P1_LSET3")
		)
		(pad "38" smd rect
			(at -1.540002 -2.899918)
			(size 0.2286 0.6096)
			(layers "F.Cu" "F.Mask" "F.Paste")
			(net "PVDDIO_P1_IMON3")
		)
		(pad "39" smd rect
			(at -1.99009 -2.899918)
			(size 0.2286 0.6096)
			(layers "F.Cu" "F.Mask" "F.Paste")
			(net "PVDDCR_CPU1_P1_VCCS")
		)
		(pad "40" smd rect
			(at -0.87503 -1.27508)
			(size 1.7526 1.9558)
			(layers "F.Cu" "F.Mask" "F.Paste")
			(net "GND")
		)
		(pad "41" smd rect
			(at -1.525016 0.249936 270)
			(size 0.3048 0.4572)
			(layers "F.Cu" "F.Mask" "F.Paste")
			(net "NC_PVDDIO_P1_GL2_3")
		)
		(zone
			(layer "F.Cu")
			(hatch none 0.5)
			(connect_pads
				(clearance 0)
			)
			(min_thickness 0.25)
			(keepout
				(tracks not_allowed)
				(vias allowed)
				(pads allowed)
				(copperpour not_allowed)
				(footprints allowed)
			)
			(placement
				(enabled no)
				(sheetname "")
			)
			(fill
				(thermal_gap 0.5)
				(thermal_bridge_width 0.5)
				(island_removal_mode 0)
			)
			(polygon
				(pts
					(xy 34.836608 -347.4212) (xy 34.836608 -348.382082) (xy 35.078924 -348.382082) (xy 35.078924 -347.4212)
				)
			)
		)
		(zone
			(layer "F.Cu")
			(hatch none 0.5)
			(connect_pads
				(clearance 0)
			)
			(min_thickness 0.25)
			(keepout
				(tracks not_allowed)
				(vias allowed)
				(pads allowed)
				(copperpour not_allowed)
				(footprints allowed)
			)
			(placement
				(enabled no)
				(sheetname "")
			)
			(fill
				(thermal_gap 0.5)
				(thermal_bridge_width 0.5)
				(island_removal_mode 0)
			)
			(polygon
				(pts
					(xy 34.380932 -344.138758) (xy 34.380932 -344.470482) (xy 39.381176 -344.470482) (xy 39.381176 -344.147648)
					(xy 39.090854 -344.147648) (xy 39.090854 -344.176858) (xy 34.671254 -344.176858) (xy 34.671254 -344.138758)
				)
			)
		)
	)
)
